(kicad_pcb
	(version 20260206)
	(generator "pcbnew")
	(generator_version "10.0")
	(general
		(thickness 1.6)
		(legacy_teardrops no)
	)
	(paper "A4")
	(title_block
		(title "panther-plus-userver — 13130-1b_20150205.brd")
		(comment 1 "Honey Badger (Wiwynn) / footprints 407-407 of 1509")
	)
	(layers
		(0 "F.Cu" signal "TOP")
		(4 "In1.Cu" signal "L2")
		(6 "In2.Cu" signal "L3")
		(8 "In3.Cu" signal "L4")
		(10 "In4.Cu" signal "L5")
		(12 "In5.Cu" signal "L6")
		(14 "In6.Cu" signal "L7")
		(16 "In7.Cu" signal "L8")
		(18 "In8.Cu" signal "L9")
		(20 "In9.Cu" signal "L10")
		(22 "In10.Cu" signal "L11")
		(2 "B.Cu" signal "BOTTOM")
		(9 "F.Adhes" user "F.Adhesive")
		(11 "B.Adhes" user "B.Adhesive")
		(13 "F.Paste" user "Package Geometry/Pastemask Top")
		(15 "B.Paste" user "Package Geometry/Pastemask Bottom")
		(5 "F.SilkS" user "Ref Des/Silkscreen Top")
		(7 "B.SilkS" user "Ref Des/Silkscreen Bottom")
		(1 "F.Mask" user "Board Geometry/Soldermask Top")
		(3 "B.Mask" user "Board Geometry/Soldermask Bottom")
		(17 "Dwgs.User" user "User.Drawings")
		(19 "Cmts.User" user "User.Comments")
		(21 "Eco1.User" user "User.Eco1")
		(23 "Eco2.User" user "User.Eco2")
		(25 "Edge.Cuts" user "Board Geometry/Outline")
		(27 "Margin" user)
		(31 "F.CrtYd" user "Package Geometry/Place Bound Top")
		(29 "B.CrtYd" user "Package Geometry/Place Bound Bottom")
		(35 "F.Fab" user "Ref Des/Assembly Top")
		(33 "B.Fab" user "Ref Des/Assembly Bottom")
	)
	(footprint ""
		(layer "F.Cu")
		(at 56.9722 -22.8346 90)
		(property "Reference" "C76"
			(at 0 0 90)
			(layer "F.SilkS")
			(hide yes)
			(effects
				(font
					(size 1.27 1.27)
				)
			)
		)
		(property "Value" "SC1U10V2KX-1GP"
			(at 1.1811 -2.7051 90)
			(unlocked yes)
			(layer "F.Fab")
			(hide yes)
			(effects
				(font
					(size 1.016 1.016)
					(thickness 0.1524)
				)
			)
		)
		(property "Device Type" "C402H22"
			(at 1.1811 -4.2291 90)
			(unlocked yes)
			(layer "F.Fab")
			(hide yes)
			(effects
				(font
					(size 1.016 1.016)
					(thickness 0.1524)
				)
			)
		)
		(duplicate_pad_numbers_are_jumpers no)
		(fp_rect
			(start -0.381 0.7366)
			(end 0.381 -0.7366)
			(stroke
				(width 0)
				(type default)
			)
			(fill no)
			(layer "F.CrtYd")
		)
		(fp_rect
			(start -0.381 0.7366)
			(end 0.381 -0.7366)
			(stroke
				(width 0)
				(type default)
			)
			(fill no)
			(layer "F.Fab")
		)
		(pad "1" smd custom
			(at 0 -0.4572 90)
			(size 0.1143 0.1143)
			(layers "F.Cu" "F.Mask" "F.Paste")
			(net "P3V3_CPU")
			(options
				(clearance outline)
				(anchor circle)
			)
			(primitives
				(gr_poly
					(pts
						(arc
							(start -0.254 -0.1778)
							(mid -0.239121 -0.213721)
							(end -0.2032 -0.2286)
						)
						(arc
							(start 0.2032 -0.2286)
							(mid 0.239121 -0.213721)
							(end 0.254 -0.1778)
						)
						(arc
							(start 0.254 0.1778)
							(mid 0.239121 0.213721)
							(end 0.2032 0.2286)
						)
						(arc
							(start -0.2032 0.2286)
							(mid -0.239121 0.213721)
							(end -0.254 0.1778)
						)
					)
					(width 0)
					(fill yes)
				)
			)
		)
		(pad "2" smd custom
			(at 0 0.4572 90)
			(size 0.1143 0.1143)
			(layers "F.Cu" "F.Mask" "F.Paste")
			(net "GND")
			(options
				(clearance outline)
				(anchor circle)
			)
			(primitives
				(gr_poly
					(pts
						(arc
							(start -0.254 -0.1778)
							(mid -0.239121 -0.213721)
							(end -0.2032 -0.2286)
						)
						(arc
							(start 0.2032 -0.2286)
							(mid 0.239121 -0.213721)
							(end 0.254 -0.1778)
						)
						(arc
							(start 0.254 0.1778)
							(mid 0.239121 0.213721)
							(end 0.2032 0.2286)
						)
						(arc
							(start -0.2032 0.2286)
							(mid -0.239121 0.213721)
							(end -0.254 0.1778)
						)
					)
					(width 0)
					(fill yes)
				)
			)
		)
	)
)
